# TIMECARD (Time Appliance Project (Time Card)) — schematic netlist excerpt (pin names and nets, part order shuffled) for the footprints in the layout excerpt that follows; sources: Cadence DE-HDL packaged netlist, KiCad conversion of R4006-B0001-02_R01.brd

C235  CAPACITOR  0.1UF 10V 10%  pkg SMC_0402R_H022  page 31 : \1\ = XP3R3V ; \2\ = SG
TP60  TP_PIONT  pkg TP010CT020B030_PTH  page 25 : \1\ = XP5R0V
R331  RESISTOR  4.7KOHM 1%  pkg SMC_0402R_H016  page 23 : \1\ = XP3R3V_FPGA ; \2\ = SMA2_SIG_OUT_BF_EN_N

(kicad_pcb
	(version 20260206)
	(generator "pcbnew")
	(generator_version "10.0")
	(general
		(thickness 1.6)
		(legacy_teardrops no)
	)
	(paper "A4")
	(title_block
		(title "timecard-production-celestica-r4006 — R4006-B0001-02_R01.brd")
		(comment 1 "Time Appliance Project (Time Card) / footprints 387-389 of 1113")
	)
	(layers
		(0 "F.Cu" signal "TOP")
		(4 "In1.Cu" signal "L02_GND1")
		(6 "In2.Cu" signal "L03_SIG1")
		(8 "In3.Cu" signal "L04_GND2")
		(10 "In4.Cu" signal "L05_VCC1")
		(12 "In5.Cu" signal "L06_VCC2")
		(14 "In6.Cu" signal "L07_GND3")
		(16 "In7.Cu" signal "L08_SIG2")
		(18 "In8.Cu" signal "L09_GND4")
		(2 "B.Cu" signal "BOTTOM")
		(9 "F.Adhes" user "F.Adhesive")
		(11 "B.Adhes" user "B.Adhesive")
		(13 "F.Paste" user "Package Geometry/Pastemask Top")
		(15 "B.Paste" user "Package Geometry/Pastemask Bottom")
		(5 "F.SilkS" user "Ref Des/Silkscreen Top")
		(7 "B.SilkS" user "Ref Des/Silkscreen Bottom")
		(1 "F.Mask" user "Board Geometry/Soldermask Top")
		(3 "B.Mask" user "Board Geometry/Soldermask Bottom")
		(17 "Dwgs.User" user "User.Drawings")
		(19 "Cmts.User" user "User.Comments")
		(21 "Eco1.User" user "User.Eco1")
		(23 "Eco2.User" user "User.Eco2")
		(25 "Edge.Cuts" user "Board Geometry/Outline")
		(27 "Margin" user)
		(31 "F.CrtYd" user "Package Geometry/Place Bound Top")
		(29 "B.CrtYd" user "Package Geometry/Place Bound Bottom")
		(35 "F.Fab" user "Ref Des/Assembly Top")
		(33 "B.Fab" user "Ref Des/Assembly Bottom")
	)
	(footprint ""
		(layer "F.Cu")
		(at 115.443 -73.533)
		(property "Reference" "C235"
			(at 3.302 0.42037 0)
			(unlocked yes)
			(layer "F.SilkS")
			(effects
				(font
					(size 0.7874 0.5842)
					(thickness 0.1524)
				)
			)
		)
		(property "Value" "VAL*"
			(at 0.0762 2.067306 0)
			(unlocked yes)
			(layer "F.Fab")
			(hide yes)
			(effects
				(font
					(size 0.7874 0.5842)
					(thickness 0.1524)
				)
			)
		)
		(property "Tolerance" "TOL*"
			(at 0.0762 3.032506 0)
			(unlocked yes)
			(layer "Cmts.User")
			(hide yes)
			(effects
				(font
					(size 0.7874 0.5842)
					(thickness 0.1524)
				)
			)
		)
		(property "User Part Number" "PARTNUM*"
			(at 0.1016 4.023106 0)
			(unlocked yes)
			(layer "Cmts.User")
			(hide yes)
			(effects
				(font
					(size 0.7874 0.5842)
					(thickness 0.1524)
				)
			)
		)
		(property "Device Type" "CAPACITOR-G105-0B104-CK,0.1UF,A"
			(at 0.0508 1.127506 0)
			(unlocked yes)
			(layer "F.Fab")
			(hide yes)
			(effects
				(font
					(size 0.7874 0.5842)
					(thickness 0.1524)
				)
			)
		)
		(duplicate_pad_numbers_are_jumpers no)
		(fp_line
			(start -1.143 -0.5588)
			(end -1.143 0.5588)
			(stroke
				(width 0.1)
				(type default)
			)
			(layer "F.SilkS")
		)
		(fp_line
			(start -1.143 0.5588)
			(end 1.143 0.5588)
			(stroke
				(width 0.1)
				(type default)
			)
			(layer "F.SilkS")
		)
		(fp_line
			(start 1.143 -0.5588)
			(end -1.143 -0.5588)
			(stroke
				(width 0.1)
				(type default)
			)
			(layer "F.SilkS")
		)
		(fp_line
			(start 1.143 0.5588)
			(end 1.143 -0.5588)
			(stroke
				(width 0.1)
				(type default)
			)
			(layer "F.SilkS")
		)
		(fp_rect
			(start 1.143 0.5588)
			(end -1.143 -0.5588)
			(stroke
				(width 0)
				(type default)
			)
			(fill no)
			(layer "F.CrtYd")
		)
		(fp_line
			(start -0.508 -0.3048)
			(end -0.508 0.3048)
			(stroke
				(width 0.1)
				(type default)
			)
			(layer "F.Fab")
		)
		(fp_line
			(start -0.508 0.3048)
			(end 0.508 0.3048)
			(stroke
				(width 0.1)
				(type default)
			)
			(layer "F.Fab")
		)
		(fp_line
			(start 0.508 -0.3048)
			(end -0.508 -0.3048)
			(stroke
				(width 0.1)
				(type default)
			)
			(layer "F.Fab")
		)
		(fp_line
			(start 0.508 0.3048)
			(end 0.508 -0.3048)
			(stroke
				(width 0.1)
				(type default)
			)
			(layer "F.Fab")
		)
		(pad "1" smd rect
			(at -0.5334 0)
			(size 0.7112 0.6096)
			(layers "F.Cu" "F.Mask" "F.Paste")
			(net "XP3R3V")
		)
		(pad "2" smd rect
			(at 0.5334 0)
			(size 0.7112 0.6096)
			(layers "F.Cu" "F.Mask" "F.Paste")
			(net "SG")
		)
		(zone
			(layer "F.Cu")
			(hatch none 0.5)
			(connect_pads
				(clearance 0)
			)
			(min_thickness 0.25)
			(keepout
				(tracks allowed)
				(vias not_allowed)
				(pads allowed)
				(copperpour not_allowed)
				(footprints allowed)
			)
			(placement
				(enabled no)
				(sheetname "")
			)
			(fill
				(thermal_gap 0.5)
				(thermal_bridge_width 0.5)
				(island_removal_mode 0)
			)
			(polygon
				(pts
					(xy 115.5192 -73.2282) (xy 115.5192 -73.8378) (xy 115.3668 -73.8378) (xy 115.3668 -73.2282)
				)
			)
		)
	)
	(footprint ""
		(layer "F.Cu")
		(at 14.605 -52.578 -90)
		(property "Reference" "R331"
			(at 0.508 3.51663 90)
			(unlocked yes)
			(layer "F.SilkS")
			(effects
				(font
					(size 0.7874 0.5842)
					(thickness 0.1524)
				)
			)
		)
		(property "Value" "VAL*"
			(at 0.02032 2.13233 270)
			(unlocked yes)
			(layer "F.Fab")
			(hide yes)
			(effects
				(font
					(size 0.7874 0.5842)
					(thickness 0.1524)
				)
			)
		)
		(property "Device Type" "RESISTOR-G155-14701-01,4.7KOHMA"
			(at 0.008382 1.210564 270)
			(unlocked yes)
			(layer "F.Fab")
			(hide yes)
			(effects
				(font
					(size 0.7874 0.5842)
					(thickness 0.1524)
				)
			)
		)
		(property "User Part Number" "PARTNUM*"
			(at 0.02032 4.024884 270)
			(unlocked yes)
			(layer "Cmts.User")
			(hide yes)
			(effects
				(font
					(size 0.7874 0.5842)
					(thickness 0.1524)
				)
			)
		)
		(property "Tolerance" "TOL*"
			(at 0.044704 3.05435 270)
			(unlocked yes)
			(layer "Cmts.User")
			(hide yes)
			(effects
				(font
					(size 0.7874 0.5842)
					(thickness 0.1524)
				)
			)
		)
		(duplicate_pad_numbers_are_jumpers no)
		(fp_line
			(start -1.143 0.5588)
			(end 1.143 0.5588)
			(stroke
				(width 0.1)
				(type default)
			)
			(layer "F.SilkS")
		)
		(fp_line
			(start 1.143 0.5588)
			(end 1.143 -0.5588)
			(stroke
				(width 0.1)
				(type default)
			)
			(layer "F.SilkS")
		)
		(fp_line
			(start -1.143 -0.5588)
			(end -1.143 0.5588)
			(stroke
				(width 0.1)
				(type default)
			)
			(layer "F.SilkS")
		)
		(fp_line
			(start 1.143 -0.5588)
			(end -1.143 -0.5588)
			(stroke
				(width 0.1)
				(type default)
			)
			(layer "F.SilkS")
		)
		(fp_rect
			(start 1.143 0.5588)
			(end -1.143 -0.5588)
			(stroke
				(width 0)
				(type default)
			)
			(fill no)
			(layer "F.CrtYd")
		)
		(fp_line
			(start -0.508 0.3048)
			(end 0.508 0.3048)
			(stroke
				(width 0.1)
				(type default)
			)
			(layer "F.Fab")
		)
		(fp_line
			(start 0.508 0.3048)
			(end 0.508 -0.3048)
			(stroke
				(width 0.1)
				(type default)
			)
			(layer "F.Fab")
		)
		(fp_line
			(start -0.508 -0.3048)
			(end -0.508 0.3048)
			(stroke
				(width 0.1)
				(type default)
			)
			(layer "F.Fab")
		)
		(fp_line
			(start 0.508 -0.3048)
			(end -0.508 -0.3048)
			(stroke
				(width 0.1)
				(type default)
			)
			(layer "F.Fab")
		)
		(pad "1" smd rect
			(at -0.5334 0 270)
			(size 0.7112 0.6096)
			(layers "F.Cu" "F.Mask" "F.Paste")
			(net "XP3R3V_FPGA")
		)
		(pad "2" smd rect
			(at 0.5334 0 270)
			(size 0.7112 0.6096)
			(layers "F.Cu" "F.Mask" "F.Paste")
			(net "SMA2_SIG_OUT_BF_EN_N")
		)
		(zone
			(layer "F.Cu")
			(hatch none 0.5)
			(connect_pads
				(clearance 0)
			)
			(min_thickness 0.25)
			(keepout
				(tracks allowed)
				(vias not_allowed)
				(pads allowed)
				(copperpour not_allowed)
				(footprints allowed)
			)
			(placement
				(enabled no)
				(sheetname "")
			)
			(fill
				(thermal_gap 0.5)
				(thermal_bridge_width 0.5)
				(island_removal_mode 0)
			)
			(polygon
				(pts
					(xy 14.3002 -52.5018) (xy 14.9098 -52.5018) (xy 14.9098 -52.6542) (xy 14.3002 -52.6542)
				)
			)
		)
	)
	(footprint ""
		(layer "F.Cu")
		(at 57.15 -100.584)
		(property "Reference" "TP60"
			(at 1.651 0.15367 0)
			(unlocked yes)
			(layer "F.SilkS")
			(effects
				(font
					(size 0.7874 0.5842)
					(thickness 0.1524)
				)
				(justify left)
			)
		)
		(property "Value" ""
			(at 0 0 0)
			(layer "F.Fab")
			(effects
				(font
					(size 1.27 1.27)
				)
			)
		)
		(property "Device Type" "TP_PIONT-TP010CT020B030_PTH-TPA"
			(at -1.341882 0.996696 0)
			(unlocked yes)
			(layer "F.Fab")
			(hide yes)
			(effects
				(font
					(size 0.7874 0.5842)
					(thickness 0.1524)
				)
				(justify left)
			)
		)
		(duplicate_pad_numbers_are_jumpers no)
		(fp_poly
			(pts
				(arc
					(start 0.889 0)
					(mid -0.889 0)
					(end 0.889 0)
				)
			)
			(stroke
				(width 0)
				(type default)
			)
			(fill no)
			(layer "B.CrtYd")
		)
		(fp_poly
			(pts
				(arc
					(start 0.889 0)
					(mid -0.889 0)
					(end 0.889 0)
				)
			)
			(stroke
				(width 0)
				(type default)
			)
			(fill no)
			(layer "F.CrtYd")
		)
		(pad "1" thru_hole circle
			(at 0 0)
			(size 0.508 0.508)
			(drill 0.254)
			(layers "*.Cu" "*.Mask")
			(remove_unused_layers no)
			(net "XP5R0V")
			(clearance 0.1016)
			(padstack
				(mode front_inner_back)
				(layer "Inner"
					(shape circle)
					(size 0.508 0.508)
					(clearance 0.1016)
				)
				(layer "B.Cu"
					(shape circle)
					(size 0.762 0.762)
					(clearance -0.0254)
				)
			)
		)
	)
)
